(kicad_pcb
	(version 20260206)
	(generator "pcbnew")
	(generator_version "10.0")
	(general
		(thickness 1.6)
		(legacy_teardrops no)
	)
	(paper "A4")
	(title_block
		(title "04192023_DAF0TMB3IC0_F0TG_MB_C_brd_V02_OCP.brd")
		(comment 1 "Grand Teton / footprints 6519-6524 of 8354")
	)
	(layers
		(0 "F.Cu" signal "TOP")
		(4 "In1.Cu" signal "GND")
		(6 "In2.Cu" signal "IN1")
		(8 "In3.Cu" signal "GND1")
		(10 "In4.Cu" signal "IN2")
		(12 "In5.Cu" signal "GND2")
		(14 "In6.Cu" signal "IN3")
		(16 "In7.Cu" signal "GND3")
		(18 "In8.Cu" signal "VCC")
		(20 "In9.Cu" signal "VCC1")
		(22 "In10.Cu" signal "GND4")
		(24 "In11.Cu" signal "IN4")
		(26 "In12.Cu" signal "GND5")
		(28 "In13.Cu" signal "IN5")
		(30 "In14.Cu" signal "GND6")
		(32 "In15.Cu" signal "IN6")
		(34 "In16.Cu" signal "GND7")
		(2 "B.Cu" signal "BOTTOM")
		(9 "F.Adhes" user "F.Adhesive")
		(11 "B.Adhes" user "B.Adhesive")
		(13 "F.Paste" user "Package Geometry/Pastemask Top")
		(15 "B.Paste" user "Package Geometry/Pastemask Bottom")
		(5 "F.SilkS" user "Ref Des/Silkscreen Top")
		(7 "B.SilkS" user "Ref Des/Silkscreen Bottom")
		(1 "F.Mask" user "Board Geometry/Soldermask Top")
		(3 "B.Mask" user "Board Geometry/Soldermask Bottom")
		(17 "Dwgs.User" user "User.Drawings")
		(19 "Cmts.User" user "User.Comments")
		(21 "Eco1.User" user "User.Eco1")
		(23 "Eco2.User" user "User.Eco2")
		(25 "Edge.Cuts" user "Board Geometry/Outline")
		(27 "Margin" user)
		(31 "F.CrtYd" user "Package Geometry/Place Bound Top")
		(29 "B.CrtYd" user "Package Geometry/Place Bound Bottom")
		(35 "F.Fab" user "Ref Des/Assembly Top")
		(33 "B.Fab" user "Ref Des/Assembly Bottom")
	)
	(footprint ""
		(layer "B.Cu")
		(at 358.465882 -256.012188 -90)
		(property "Reference" "C2553"
			(at 0 0 90)
			(layer "B.SilkS")
			(hide yes)
			(effects
				(font
					(size 1.27 1.27)
				)
				(justify mirror)
			)
		)
		(property "Value" ""
			(at 0 0 90)
			(layer "B.Fab")
			(effects
				(font
					(size 1.27 1.27)
				)
				(justify mirror)
			)
		)
		(duplicate_pad_numbers_are_jumpers no)
		(fp_line
			(start -0.7874 0.4064)
			(end 0.7874 0.4064)
			(stroke
				(width 0.1524)
				(type default)
			)
			(layer "B.SilkS")
		)
		(fp_line
			(start 0.7874 0.4064)
			(end 0.7874 -0.4064)
			(stroke
				(width 0.1524)
				(type default)
			)
			(layer "B.SilkS")
		)
		(fp_line
			(start -0.7874 -0.4064)
			(end -0.7874 0.4064)
			(stroke
				(width 0.1524)
				(type default)
			)
			(layer "B.SilkS")
		)
		(fp_line
			(start 0.7874 -0.4064)
			(end -0.7874 -0.4064)
			(stroke
				(width 0.1524)
				(type default)
			)
			(layer "B.SilkS")
		)
		(fp_line
			(start -0.67945 0.3048)
			(end -0.120396 0.3048)
			(stroke
				(width 0.1)
				(type default)
			)
			(layer "B.Fab")
		)
		(fp_line
			(start -0.120396 0.3048)
			(end -0.120396 0.2794)
			(stroke
				(width 0.1)
				(type default)
			)
			(layer "B.Fab")
		)
		(fp_line
			(start 0.12065 0.3048)
			(end 0.67945 0.3048)
			(stroke
				(width 0.1)
				(type default)
			)
			(layer "B.Fab")
		)
		(fp_line
			(start 0.67945 0.3048)
			(end 0.67945 -0.305054)
			(stroke
				(width 0.1)
				(type default)
			)
			(layer "B.Fab")
		)
		(fp_line
			(start -0.120396 0.2794)
			(end 0.12065 0.2794)
			(stroke
				(width 0.1)
				(type default)
			)
			(layer "B.Fab")
		)
		(fp_line
			(start 0.12065 0.2794)
			(end 0.12065 0.3048)
			(stroke
				(width 0.1)
				(type default)
			)
			(layer "B.Fab")
		)
		(fp_line
			(start -0.12065 -0.2794)
			(end -0.12065 -0.3048)
			(stroke
				(width 0.1)
				(type default)
			)
			(layer "B.Fab")
		)
		(fp_line
			(start 0.12065 -0.2794)
			(end -0.12065 -0.2794)
			(stroke
				(width 0.1)
				(type default)
			)
			(layer "B.Fab")
		)
		(fp_line
			(start -0.67945 -0.3048)
			(end -0.67945 0.3048)
			(stroke
				(width 0.1)
				(type default)
			)
			(layer "B.Fab")
		)
		(fp_line
			(start -0.12065 -0.3048)
			(end -0.67945 -0.3048)
			(stroke
				(width 0.1)
				(type default)
			)
			(layer "B.Fab")
		)
		(fp_line
			(start 0.12065 -0.305054)
			(end 0.12065 -0.2794)
			(stroke
				(width 0.1)
				(type default)
			)
			(layer "B.Fab")
		)
		(fp_line
			(start 0.67945 -0.305054)
			(end 0.12065 -0.305054)
			(stroke
				(width 0.1)
				(type default)
			)
			(layer "B.Fab")
		)
		(pad "1" smd circle
			(at 0.40005 0 90)
			(size 0 0)
			(layers "B.Cu" "B.Mask" "B.Paste")
			(net "PVDDCR_SOC_P0")
		)
		(pad "2" smd circle
			(at -0.40005 0 90)
			(size 0 0)
			(layers "B.Cu" "B.Mask" "B.Paste")
			(net "GND")
		)
	)
	(footprint ""
		(layer "B.Cu")
		(at 107.917996 -26.952448 90)
		(property "Reference" "C6100"
			(at 0 0 90)
			(layer "B.SilkS")
			(hide yes)
			(effects
				(font
					(size 1.27 1.27)
				)
				(justify mirror)
			)
		)
		(property "Value" ""
			(at 0 0 90)
			(layer "B.Fab")
			(effects
				(font
					(size 1.27 1.27)
				)
				(justify mirror)
			)
		)
		(duplicate_pad_numbers_are_jumpers no)
		(fp_line
			(start 0.7874 -0.4064)
			(end -0.7874 -0.4064)
			(stroke
				(width 0.1524)
				(type default)
			)
			(layer "B.SilkS")
		)
		(fp_line
			(start -0.7874 -0.4064)
			(end -0.7874 0.4064)
			(stroke
				(width 0.1524)
				(type default)
			)
			(layer "B.SilkS")
		)
		(fp_line
			(start 0.7874 0.4064)
			(end 0.7874 -0.4064)
			(stroke
				(width 0.1524)
				(type default)
			)
			(layer "B.SilkS")
		)
		(fp_line
			(start -0.7874 0.4064)
			(end 0.7874 0.4064)
			(stroke
				(width 0.1524)
				(type default)
			)
			(layer "B.SilkS")
		)
		(fp_line
			(start 0.67945 -0.305054)
			(end 0.12065 -0.305054)
			(stroke
				(width 0.1)
				(type default)
			)
			(layer "B.Fab")
		)
		(fp_line
			(start 0.12065 -0.305054)
			(end 0.12065 -0.2794)
			(stroke
				(width 0.1)
				(type default)
			)
			(layer "B.Fab")
		)
		(fp_line
			(start -0.12065 -0.3048)
			(end -0.67945 -0.3048)
			(stroke
				(width 0.1)
				(type default)
			)
			(layer "B.Fab")
		)
		(fp_line
			(start -0.67945 -0.3048)
			(end -0.67945 0.3048)
			(stroke
				(width 0.1)
				(type default)
			)
			(layer "B.Fab")
		)
		(fp_line
			(start 0.12065 -0.2794)
			(end -0.12065 -0.2794)
			(stroke
				(width 0.1)
				(type default)
			)
			(layer "B.Fab")
		)
		(fp_line
			(start -0.12065 -0.2794)
			(end -0.12065 -0.3048)
			(stroke
				(width 0.1)
				(type default)
			)
			(layer "B.Fab")
		)
		(fp_line
			(start 0.12065 0.2794)
			(end 0.12065 0.3048)
			(stroke
				(width 0.1)
				(type default)
			)
			(layer "B.Fab")
		)
		(fp_line
			(start -0.120396 0.2794)
			(end 0.12065 0.2794)
			(stroke
				(width 0.1)
				(type default)
			)
			(layer "B.Fab")
		)
		(fp_line
			(start 0.67945 0.3048)
			(end 0.67945 -0.305054)
			(stroke
				(width 0.1)
				(type default)
			)
			(layer "B.Fab")
		)
		(fp_line
			(start 0.12065 0.3048)
			(end 0.67945 0.3048)
			(stroke
				(width 0.1)
				(type default)
			)
			(layer "B.Fab")
		)
		(fp_line
			(start -0.120396 0.3048)
			(end -0.120396 0.2794)
			(stroke
				(width 0.1)
				(type default)
			)
			(layer "B.Fab")
		)
		(fp_line
			(start -0.67945 0.3048)
			(end -0.120396 0.3048)
			(stroke
				(width 0.1)
				(type default)
			)
			(layer "B.Fab")
		)
		(pad "1" smd circle
			(at 0.40005 0 270)
			(size 0 0)
			(layers "B.Cu" "B.Mask" "B.Paste")
			(net "P3V3_AUX_CPU0_USB2_AVDD33")
		)
		(pad "2" smd circle
			(at -0.40005 0 270)
			(size 0 0)
			(layers "B.Cu" "B.Mask" "B.Paste")
			(net "GND")
		)
	)
	(footprint ""
		(layer "B.Cu")
		(at 114.467386 -268.418564)
		(property "Reference" "C2387"
			(at 0 0 0)
			(layer "B.SilkS")
			(hide yes)
			(effects
				(font
					(size 1.27 1.27)
				)
				(justify mirror)
			)
		)
		(property "Value" ""
			(at 0 0 0)
			(layer "B.Fab")
			(effects
				(font
					(size 1.27 1.27)
				)
				(justify mirror)
			)
		)
		(duplicate_pad_numbers_are_jumpers no)
		(fp_line
			(start -0.7874 -0.4064)
			(end -0.7874 0.4064)
			(stroke
				(width 0.1524)
				(type default)
			)
			(layer "B.SilkS")
		)
		(fp_line
			(start -0.7874 0.4064)
			(end 0.7874 0.4064)
			(stroke
				(width 0.1524)
				(type default)
			)
			(layer "B.SilkS")
		)
		(fp_line
			(start 0.7874 -0.4064)
			(end -0.7874 -0.4064)
			(stroke
				(width 0.1524)
				(type default)
			)
			(layer "B.SilkS")
		)
		(fp_line
			(start 0.7874 0.4064)
			(end 0.7874 -0.4064)
			(stroke
				(width 0.1524)
				(type default)
			)
			(layer "B.SilkS")
		)
		(fp_line
			(start -0.67945 -0.3048)
			(end -0.67945 0.3048)
			(stroke
				(width 0.1)
				(type default)
			)
			(layer "B.Fab")
		)
		(fp_line
			(start -0.67945 0.3048)
			(end -0.120396 0.3048)
			(stroke
				(width 0.1)
				(type default)
			)
			(layer "B.Fab")
		)
		(fp_line
			(start -0.12065 -0.3048)
			(end -0.67945 -0.3048)
			(stroke
				(width 0.1)
				(type default)
			)
			(layer "B.Fab")
		)
		(fp_line
			(start -0.12065 -0.2794)
			(end -0.12065 -0.3048)
			(stroke
				(width 0.1)
				(type default)
			)
			(layer "B.Fab")
		)
		(fp_line
			(start -0.120396 0.2794)
			(end 0.12065 0.2794)
			(stroke
				(width 0.1)
				(type default)
			)
			(layer "B.Fab")
		)
		(fp_line
			(start -0.120396 0.3048)
			(end -0.120396 0.2794)
			(stroke
				(width 0.1)
				(type default)
			)
			(layer "B.Fab")
		)
		(fp_line
			(start 0.12065 -0.305054)
			(end 0.12065 -0.2794)
			(stroke
				(width 0.1)
				(type default)
			)
			(layer "B.Fab")
		)
		(fp_line
			(start 0.12065 -0.2794)
			(end -0.12065 -0.2794)
			(stroke
				(width 0.1)
				(type default)
			)
			(layer "B.Fab")
		)
		(fp_line
			(start 0.12065 0.2794)
			(end 0.12065 0.3048)
			(stroke
				(width 0.1)
				(type default)
			)
			(layer "B.Fab")
		)
		(fp_line
			(start 0.12065 0.3048)
			(end 0.67945 0.3048)
			(stroke
				(width 0.1)
				(type default)
			)
			(layer "B.Fab")
		)
		(fp_line
			(start 0.67945 -0.305054)
			(end 0.12065 -0.305054)
			(stroke
				(width 0.1)
				(type default)
			)
			(layer "B.Fab")
		)
		(fp_line
			(start 0.67945 0.3048)
			(end 0.67945 -0.305054)
			(stroke
				(width 0.1)
				(type default)
			)
			(layer "B.Fab")
		)
		(pad "1" smd circle
			(at 0.40005 0 180)
			(size 0 0)
			(layers "B.Cu" "B.Mask" "B.Paste")
			(net "PVDDCR_CPU1_P1")
		)
		(pad "2" smd circle
			(at -0.40005 0 180)
			(size 0 0)
			(layers "B.Cu" "B.Mask" "B.Paste")
			(net "GND")
		)
	)
	(footprint ""
		(layer "B.Cu")
		(at 348.913958 -250.89231 180)
		(property "Reference" "C2514"
			(at 0 0 0)
			(layer "B.SilkS")
			(hide yes)
			(effects
				(font
					(size 1.27 1.27)
				)
				(justify mirror)
			)
		)
		(property "Value" ""
			(at 0 0 0)
			(layer "B.Fab")
			(effects
				(font
					(size 1.27 1.27)
				)
				(justify mirror)
			)
		)
		(duplicate_pad_numbers_are_jumpers no)
		(fp_line
			(start 0.7874 0.4064)
			(end 0.7874 -0.4064)
			(stroke
				(width 0.1524)
				(type default)
			)
			(layer "B.SilkS")
		)
		(fp_line
			(start 0.7874 -0.4064)
			(end -0.7874 -0.4064)
			(stroke
				(width 0.1524)
				(type default)
			)
			(layer "B.SilkS")
		)
		(fp_line
			(start -0.7874 0.4064)
			(end 0.7874 0.4064)
			(stroke
				(width 0.1524)
				(type default)
			)
			(layer "B.SilkS")
		)
		(fp_line
			(start -0.7874 -0.4064)
			(end -0.7874 0.4064)
			(stroke
				(width 0.1524)
				(type default)
			)
			(layer "B.SilkS")
		)
		(fp_line
			(start 0.67945 0.3048)
			(end 0.67945 -0.305054)
			(stroke
				(width 0.1)
				(type default)
			)
			(layer "B.Fab")
		)
		(fp_line
			(start 0.67945 -0.305054)
			(end 0.12065 -0.305054)
			(stroke
				(width 0.1)
				(type default)
			)
			(layer "B.Fab")
		)
		(fp_line
			(start 0.12065 0.3048)
			(end 0.67945 0.3048)
			(stroke
				(width 0.1)
				(type default)
			)
			(layer "B.Fab")
		)
		(fp_line
			(start 0.12065 0.2794)
			(end 0.12065 0.3048)
			(stroke
				(width 0.1)
				(type default)
			)
			(layer "B.Fab")
		)
		(fp_line
			(start 0.12065 -0.2794)
			(end -0.12065 -0.2794)
			(stroke
				(width 0.1)
				(type default)
			)
			(layer "B.Fab")
		)
		(fp_line
			(start 0.12065 -0.305054)
			(end 0.12065 -0.2794)
			(stroke
				(width 0.1)
				(type default)
			)
			(layer "B.Fab")
		)
		(fp_line
			(start -0.120396 0.3048)
			(end -0.120396 0.2794)
			(stroke
				(width 0.1)
				(type default)
			)
			(layer "B.Fab")
		)
		(fp_line
			(start -0.120396 0.2794)
			(end 0.12065 0.2794)
			(stroke
				(width 0.1)
				(type default)
			)
			(layer "B.Fab")
		)
		(fp_line
			(start -0.12065 -0.2794)
			(end -0.12065 -0.3048)
			(stroke
				(width 0.1)
				(type default)
			)
			(layer "B.Fab")
		)
		(fp_line
			(start -0.12065 -0.3048)
			(end -0.67945 -0.3048)
			(stroke
				(width 0.1)
				(type default)
			)
			(layer "B.Fab")
		)
		(fp_line
			(start -0.67945 0.3048)
			(end -0.120396 0.3048)
			(stroke
				(width 0.1)
				(type default)
			)
			(layer "B.Fab")
		)
		(fp_line
			(start -0.67945 -0.3048)
			(end -0.67945 0.3048)
			(stroke
				(width 0.1)
				(type default)
			)
			(layer "B.Fab")
		)
		(pad "1" smd circle
			(at 0.40005 0)
			(size 0 0)
			(layers "B.Cu" "B.Mask" "B.Paste")
			(net "PVDD18_S5_P0")
		)
		(pad "2" smd circle
			(at -0.40005 0)
			(size 0 0)
			(layers "B.Cu" "B.Mask" "B.Paste")
			(net "GND")
		)
	)
	(footprint ""
		(layer "B.Cu")
		(at 126.894844 -41.762172 -90)
		(property "Reference" "C6079"
			(at 0 0 90)
			(layer "B.SilkS")
			(hide yes)
			(effects
				(font
					(size 1.27 1.27)
				)
				(justify mirror)
			)
		)
		(property "Value" ""
			(at 0 0 90)
			(layer "B.Fab")
			(effects
				(font
					(size 1.27 1.27)
				)
				(justify mirror)
			)
		)
		(duplicate_pad_numbers_are_jumpers no)
		(fp_line
			(start -1.2954 0.5842)
			(end 1.2954 0.5842)
			(stroke
				(width 0.1524)
				(type default)
			)
			(layer "B.SilkS")
		)
		(fp_line
			(start 1.2954 0.5842)
			(end 1.2954 -0.5842)
			(stroke
				(width 0.1524)
				(type default)
			)
			(layer "B.SilkS")
		)
		(fp_line
			(start -1.2954 -0.5842)
			(end -1.2954 0.5842)
			(stroke
				(width 0.1524)
				(type default)
			)
			(layer "B.SilkS")
		)
		(fp_line
			(start 1.2954 -0.5842)
			(end -1.2954 -0.5842)
			(stroke
				(width 0.1524)
				(type default)
			)
			(layer "B.SilkS")
		)
		(fp_line
			(start -0.8636 0.4572)
			(end 0.8636 0.4572)
			(stroke
				(width 0.1)
				(type default)
			)
			(layer "B.Fab")
		)
		(fp_line
			(start 0.8636 0.4572)
			(end 0.8636 0.4064)
			(stroke
				(width 0.1)
				(type default)
			)
			(layer "B.Fab")
		)
		(fp_line
			(start -1.1938 0.4064)
			(end -0.8636 0.4064)
			(stroke
				(width 0.1)
				(type default)
			)
			(layer "B.Fab")
		)
		(fp_line
			(start -0.8636 0.4064)
			(end -0.8636 0.4572)
			(stroke
				(width 0.1)
				(type default)
			)
			(layer "B.Fab")
		)
		(fp_line
			(start 0.8636 0.4064)
			(end 1.1938 0.4064)
			(stroke
				(width 0.1)
				(type default)
			)
			(layer "B.Fab")
		)
		(fp_line
			(start 1.1938 0.4064)
			(end 1.1938 -0.4064)
			(stroke
				(width 0.1)
				(type default)
			)
			(layer "B.Fab")
		)
		(fp_line
			(start -1.1938 -0.4064)
			(end -1.1938 0.4064)
			(stroke
				(width 0.1)
				(type default)
			)
			(layer "B.Fab")
		)
		(fp_line
			(start -0.8636 -0.4064)
			(end -1.1938 -0.4064)
			(stroke
				(width 0.1)
				(type default)
			)
			(layer "B.Fab")
		)
		(fp_line
			(start 0.8636 -0.4064)
			(end 0.8636 -0.4572)
			(stroke
				(width 0.1)
				(type default)
			)
			(layer "B.Fab")
		)
		(fp_line
			(start 1.1938 -0.4064)
			(end 0.8636 -0.4064)
			(stroke
				(width 0.1)
				(type default)
			)
			(layer "B.Fab")
		)
		(fp_line
			(start -0.8636 -0.4572)
			(end -0.8636 -0.4064)
			(stroke
				(width 0.1)
				(type default)
			)
			(layer "B.Fab")
		)
		(fp_line
			(start 0.8636 -0.4572)
			(end -0.8636 -0.4572)
			(stroke
				(width 0.1)
				(type default)
			)
			(layer "B.Fab")
		)
		(pad "1" smd rect
			(at 0.7366 0 180)
			(size 0.7112 0.8128)
			(layers "B.Cu" "B.Mask" "B.Paste")
			(net "P1V2_AUX")
		)
		(pad "2" smd rect
			(at -0.7366 0 180)
			(size 0.7112 0.8128)
			(layers "B.Cu" "B.Mask" "B.Paste")
			(net "GND")
		)
	)
	(footprint ""
		(layer "B.Cu")
		(at 130.458972 -41.007792 90)
		(property "Reference" "C6041"
			(at 0 0 90)
			(layer "B.SilkS")
			(hide yes)
			(effects
				(font
					(size 1.27 1.27)
				)
				(justify mirror)
			)
		)
		(property "Value" ""
			(at 0 0 90)
			(layer "B.Fab")
			(effects
				(font
					(size 1.27 1.27)
				)
				(justify mirror)
			)
		)
		(duplicate_pad_numbers_are_jumpers no)
		(fp_line
			(start 0.7874 -0.4064)
			(end -0.7874 -0.4064)
			(stroke
				(width 0.1524)
				(type default)
			)
			(layer "B.SilkS")
		)
		(fp_line
			(start -0.7874 -0.4064)
			(end -0.7874 0.4064)
			(stroke
				(width 0.1524)
				(type default)
			)
			(layer "B.SilkS")
		)
		(fp_line
			(start 0.7874 0.4064)
			(end 0.7874 -0.4064)
			(stroke
				(width 0.1524)
				(type default)
			)
			(layer "B.SilkS")
		)
		(fp_line
			(start -0.7874 0.4064)
			(end 0.7874 0.4064)
			(stroke
				(width 0.1524)
				(type default)
			)
			(layer "B.SilkS")
		)
		(fp_line
			(start 0.67945 -0.305054)
			(end 0.12065 -0.305054)
			(stroke
				(width 0.1)
				(type default)
			)
			(layer "B.Fab")
		)
		(fp_line
			(start 0.12065 -0.305054)
			(end 0.12065 -0.2794)
			(stroke
				(width 0.1)
				(type default)
			)
			(layer "B.Fab")
		)
		(fp_line
			(start -0.12065 -0.3048)
			(end -0.67945 -0.3048)
			(stroke
				(width 0.1)
				(type default)
			)
			(layer "B.Fab")
		)
		(fp_line
			(start -0.67945 -0.3048)
			(end -0.67945 0.3048)
			(stroke
				(width 0.1)
				(type default)
			)
			(layer "B.Fab")
		)
		(fp_line
			(start 0.12065 -0.2794)
			(end -0.12065 -0.2794)
			(stroke
				(width 0.1)
				(type default)
			)
			(layer "B.Fab")
		)
		(fp_line
			(start -0.12065 -0.2794)
			(end -0.12065 -0.3048)
			(stroke
				(width 0.1)
				(type default)
			)
			(layer "B.Fab")
		)
		(fp_line
			(start 0.12065 0.2794)
			(end 0.12065 0.3048)
			(stroke
				(width 0.1)
				(type default)
			)
			(layer "B.Fab")
		)
		(fp_line
			(start -0.120396 0.2794)
			(end 0.12065 0.2794)
			(stroke
				(width 0.1)
				(type default)
			)
			(layer "B.Fab")
		)
		(fp_line
			(start 0.67945 0.3048)
			(end 0.67945 -0.305054)
			(stroke
				(width 0.1)
				(type default)
			)
			(layer "B.Fab")
		)
		(fp_line
			(start 0.12065 0.3048)
			(end 0.67945 0.3048)
			(stroke
				(width 0.1)
				(type default)
			)
			(layer "B.Fab")
		)
		(fp_line
			(start -0.120396 0.3048)
			(end -0.120396 0.2794)
			(stroke
				(width 0.1)
				(type default)
			)
			(layer "B.Fab")
		)
		(fp_line
			(start -0.67945 0.3048)
			(end -0.120396 0.3048)
			(stroke
				(width 0.1)
				(type default)
			)
			(layer "B.Fab")
		)
		(pad "1" smd circle
			(at 0.40005 0 270)
			(size 0 0)
			(layers "B.Cu" "B.Mask" "B.Paste")
			(net "P3V3_AUX")
		)
		(pad "2" smd circle
			(at -0.40005 0 270)
			(size 0 0)
			(layers "B.Cu" "B.Mask" "B.Paste")
			(net "GND")
		)
	)
)
